(kicad_pcb
	(version 20260206)
	(generator "pcbnew")
	(generator_version "10.0")
	(general
		(thickness 1.6)
		(legacy_teardrops no)
	)
	(paper "A4")
	(title_block
		(title "Wiwynn_Tioga_Pass_MB.brd")
		(comment 1 "Tioga Pass / footprints 3714-3720 of 4770")
	)
	(layers
		(0 "F.Cu" signal "TOP")
		(4 "In1.Cu" signal "L2GND")
		(6 "In2.Cu" signal "L3")
		(8 "In3.Cu" signal "L4GND")
		(10 "In4.Cu" signal "L5")
		(12 "In5.Cu" signal "L6GND")
		(14 "In6.Cu" signal "L7VCC")
		(16 "In7.Cu" signal "L8VCC")
		(18 "In8.Cu" signal "L9GND")
		(20 "In9.Cu" signal "L10")
		(22 "In10.Cu" signal "L11GND")
		(24 "In11.Cu" signal "L12")
		(26 "In12.Cu" signal "L13GND")
		(2 "B.Cu" signal "BOTTOM")
		(9 "F.Adhes" user "F.Adhesive")
		(11 "B.Adhes" user "B.Adhesive")
		(13 "F.Paste" user "Package Geometry/Pastemask Top")
		(15 "B.Paste" user "Package Geometry/Pastemask Bottom")
		(5 "F.SilkS" user "Ref Des/Silkscreen Top")
		(7 "B.SilkS" user "Ref Des/Silkscreen Bottom")
		(1 "F.Mask" user "Board Geometry/Soldermask Top")
		(3 "B.Mask" user "Board Geometry/Soldermask Bottom")
		(17 "Dwgs.User" user "User.Drawings")
		(19 "Cmts.User" user "User.Comments")
		(21 "Eco1.User" user "User.Eco1")
		(23 "Eco2.User" user "User.Eco2")
		(25 "Edge.Cuts" user "Board Geometry/Outline")
		(27 "Margin" user)
		(31 "F.CrtYd" user "Package Geometry/Place Bound Top")
		(29 "B.CrtYd" user "Package Geometry/Place Bound Bottom")
		(35 "F.Fab" user "Ref Des/Assembly Top")
		(33 "B.Fab" user "Ref Des/Assembly Bottom")
	)
	(footprint ""
		(layer "B.Cu")
		(at 168.148 -123.19 180)
		(property "Reference" "R6M9"
			(at 0 0 0)
			(layer "B.SilkS")
			(hide yes)
			(effects
				(font
					(size 1.27 1.27)
				)
				(justify mirror)
			)
		)
		(property "Value" ""
			(at 0 0 0)
			(layer "B.Fab")
			(effects
				(font
					(size 1.27 1.27)
				)
				(justify mirror)
			)
		)
		(duplicate_pad_numbers_are_jumpers no)
		(fp_poly
			(pts
				(xy 0.2794 -0.1016) (xy -0.2794 -0.1016) (xy -0.2794 0.9906) (xy 0.2794 0.9906)
			)
			(stroke
				(width 0)
				(type default)
			)
			(fill no)
			(layer "B.CrtYd")
		)
		(fp_line
			(start 0.2794 0.9906)
			(end -0.2794 0.9906)
			(stroke
				(width 0.1)
				(type default)
			)
			(layer "B.Fab")
		)
		(fp_line
			(start 0.2794 -0.1016)
			(end 0.2794 0.9906)
			(stroke
				(width 0.1)
				(type default)
			)
			(layer "B.Fab")
		)
		(fp_line
			(start -0.2794 0.9906)
			(end -0.2794 -0.1016)
			(stroke
				(width 0.1)
				(type default)
			)
			(layer "B.Fab")
		)
		(fp_line
			(start -0.2794 -0.1016)
			(end 0.2794 -0.1016)
			(stroke
				(width 0.1)
				(type default)
			)
			(layer "B.Fab")
		)
		(pad "1" smd rect
			(at 0 0)
			(size 0.508 0.508)
			(layers "B.Cu" "B.Mask" "B.Paste")
			(net "PVPP_KLM")
		)
		(pad "2" smd rect
			(at 0 0.889)
			(size 0.508 0.508)
			(layers "B.Cu" "B.Mask" "B.Paste")
			(net "RST_CD_CPU1_POR_N")
		)
		(zone
			(layer "B.Cu")
			(hatch none 0.5)
			(connect_pads
				(clearance 0)
			)
			(min_thickness 0.25)
			(keepout
				(tracks not_allowed)
				(vias allowed)
				(pads allowed)
				(copperpour not_allowed)
				(footprints allowed)
			)
			(placement
				(enabled no)
				(sheetname "")
			)
			(fill
				(thermal_gap 0.5)
				(thermal_bridge_width 0.5)
				(island_removal_mode 0)
			)
			(polygon
				(pts
					(xy 167.894 -123.825) (xy 168.402 -123.825) (xy 168.402 -123.444) (xy 167.894 -123.444)
				)
			)
		)
		(zone
			(layer "B.Cu")
			(hatch none 0.5)
			(connect_pads
				(clearance 0)
			)
			(min_thickness 0.25)
			(keepout
				(tracks allowed)
				(vias not_allowed)
				(pads allowed)
				(copperpour not_allowed)
				(footprints allowed)
			)
			(placement
				(enabled no)
				(sheetname "")
			)
			(fill
				(thermal_gap 0.5)
				(thermal_bridge_width 0.5)
				(island_removal_mode 0)
			)
			(polygon
				(pts
					(xy 167.894 -123.444) (xy 168.402 -123.444) (xy 168.402 -123.825) (xy 167.894 -123.825)
				)
			)
		)
	)
	(footprint ""
		(layer "B.Cu")
		(at 252.1585 -12.954 -90)
		(property "Reference" "C5G43"
			(at -1.14681 0.76708 0)
			(unlocked yes)
			(layer "B.SilkS")
			(effects
				(font
					(size 0.7874 0.5842)
					(thickness 0.1524)
				)
				(justify mirror)
			)
		)
		(property "Value" ""
			(at 0 0 90)
			(layer "B.Fab")
			(effects
				(font
					(size 1.27 1.27)
				)
				(justify mirror)
			)
		)
		(duplicate_pad_numbers_are_jumpers no)
		(fp_rect
			(start 0.4953 1.6002)
			(end -0.4953 -0.2032)
			(stroke
				(width 0)
				(type default)
			)
			(fill no)
			(layer "B.CrtYd")
		)
		(fp_line
			(start -0.4953 1.6002)
			(end 0.4953 1.6002)
			(stroke
				(width 0.1)
				(type default)
			)
			(layer "B.Fab")
		)
		(fp_line
			(start 0.4953 1.6002)
			(end 0.4953 -0.2032)
			(stroke
				(width 0.1)
				(type default)
			)
			(layer "B.Fab")
		)
		(fp_line
			(start -0.4953 -0.2032)
			(end -0.4953 1.6002)
			(stroke
				(width 0.1)
				(type default)
			)
			(layer "B.Fab")
		)
		(fp_line
			(start 0.4953 -0.2032)
			(end -0.4953 -0.2032)
			(stroke
				(width 0.1)
				(type default)
			)
			(layer "B.Fab")
		)
		(pad "1" smd rect
			(at 0 0 90)
			(size 0.762 0.889)
			(layers "B.Cu" "B.Mask" "B.Paste")
			(net "PVDDQ_ABC")
		)
		(pad "2" smd rect
			(at 0 1.397 90)
			(size 0.762 0.889)
			(layers "B.Cu" "B.Mask" "B.Paste")
			(net "GND")
		)
		(zone
			(layer "B.Cu")
			(hatch none 0.5)
			(connect_pads
				(clearance 0)
			)
			(min_thickness 0.25)
			(keepout
				(tracks not_allowed)
				(vias allowed)
				(pads allowed)
				(copperpour not_allowed)
				(footprints allowed)
			)
			(placement
				(enabled no)
				(sheetname "")
			)
			(fill
				(thermal_gap 0.5)
				(thermal_bridge_width 0.5)
				(island_removal_mode 0)
			)
			(polygon
				(pts
					(xy 251.206 -12.573) (xy 251.714 -12.573) (xy 251.714 -13.335) (xy 251.206 -13.335)
				)
			)
		)
	)
	(footprint ""
		(layer "B.Cu")
		(at 349.0214 -155.7274 -90)
		(property "Reference" "R3L6"
			(at 0 0 90)
			(layer "B.SilkS")
			(hide yes)
			(effects
				(font
					(size 1.27 1.27)
				)
				(justify mirror)
			)
		)
		(property "Value" ""
			(at 0 0 90)
			(layer "B.Fab")
			(effects
				(font
					(size 1.27 1.27)
				)
				(justify mirror)
			)
		)
		(duplicate_pad_numbers_are_jumpers no)
		(fp_poly
			(pts
				(xy 0.2794 -0.1016) (xy -0.2794 -0.1016) (xy -0.2794 0.9906) (xy 0.2794 0.9906)
			)
			(stroke
				(width 0)
				(type default)
			)
			(fill no)
			(layer "B.CrtYd")
		)
		(fp_line
			(start -0.2794 0.9906)
			(end -0.2794 -0.1016)
			(stroke
				(width 0.1)
				(type default)
			)
			(layer "B.Fab")
		)
		(fp_line
			(start 0.2794 0.9906)
			(end -0.2794 0.9906)
			(stroke
				(width 0.1)
				(type default)
			)
			(layer "B.Fab")
		)
		(fp_line
			(start -0.2794 -0.1016)
			(end 0.2794 -0.1016)
			(stroke
				(width 0.1)
				(type default)
			)
			(layer "B.Fab")
		)
		(fp_line
			(start 0.2794 -0.1016)
			(end 0.2794 0.9906)
			(stroke
				(width 0.1)
				(type default)
			)
			(layer "B.Fab")
		)
		(pad "1" smd rect
			(at 0 0 90)
			(size 0.508 0.508)
			(layers "B.Cu" "B.Mask" "B.Paste")
			(net "VR_PVDDQ_DEF_PH1_VCIN")
		)
		(pad "2" smd rect
			(at 0 0.889 90)
			(size 0.508 0.508)
			(layers "B.Cu" "B.Mask" "B.Paste")
			(net "P5V_STBY")
		)
		(zone
			(layer "B.Cu")
			(hatch none 0.5)
			(connect_pads
				(clearance 0)
			)
			(min_thickness 0.25)
			(keepout
				(tracks not_allowed)
				(vias allowed)
				(pads allowed)
				(copperpour not_allowed)
				(footprints allowed)
			)
			(placement
				(enabled no)
				(sheetname "")
			)
			(fill
				(thermal_gap 0.5)
				(thermal_bridge_width 0.5)
				(island_removal_mode 0)
			)
			(polygon
				(pts
					(xy 348.3864 -155.4734) (xy 348.3864 -155.9814) (xy 348.7674 -155.9814) (xy 348.7674 -155.4734)
				)
			)
		)
		(zone
			(layer "B.Cu")
			(hatch none 0.5)
			(connect_pads
				(clearance 0)
			)
			(min_thickness 0.25)
			(keepout
				(tracks allowed)
				(vias not_allowed)
				(pads allowed)
				(copperpour not_allowed)
				(footprints allowed)
			)
			(placement
				(enabled no)
				(sheetname "")
			)
			(fill
				(thermal_gap 0.5)
				(thermal_bridge_width 0.5)
				(island_removal_mode 0)
			)
			(polygon
				(pts
					(xy 348.7674 -155.4734) (xy 348.7674 -155.9814) (xy 348.3864 -155.9814) (xy 348.3864 -155.4734)
				)
			)
		)
	)
	(footprint ""
		(layer "B.Cu")
		(at 477.634554 -2.513838 -90)
		(property "Reference" "C9G12"
			(at 0 0 90)
			(layer "B.SilkS")
			(hide yes)
			(effects
				(font
					(size 1.27 1.27)
				)
				(justify mirror)
			)
		)
		(property "Value" ""
			(at 0 0 90)
			(layer "B.Fab")
			(effects
				(font
					(size 1.27 1.27)
				)
				(justify mirror)
			)
		)
		(duplicate_pad_numbers_are_jumpers no)
		(fp_poly
			(pts
				(xy -0.3048 -0.1016) (xy -0.3048 0.9906) (xy 0.3048 0.9906) (xy 0.3048 -0.1016)
			)
			(stroke
				(width 0)
				(type default)
			)
			(fill no)
			(layer "B.CrtYd")
		)
		(fp_line
			(start -0.3048 0.9906)
			(end -0.3048 -0.1016)
			(stroke
				(width 0.1)
				(type default)
			)
			(layer "B.Fab")
		)
		(fp_line
			(start 0.3048 0.9906)
			(end -0.3048 0.9906)
			(stroke
				(width 0.1)
				(type default)
			)
			(layer "B.Fab")
		)
		(fp_line
			(start -0.3048 -0.1016)
			(end 0.3048 -0.1016)
			(stroke
				(width 0.1)
				(type default)
			)
			(layer "B.Fab")
		)
		(fp_line
			(start 0.3048 -0.1016)
			(end 0.3048 0.9906)
			(stroke
				(width 0.1)
				(type default)
			)
			(layer "B.Fab")
		)
		(pad "1" smd rect
			(at 0 0 90)
			(size 0.508 0.508)
			(layers "B.Cu" "B.Mask" "B.Paste")
			(net "NIC_SER_N_MDI_3_DN")
		)
		(pad "2" smd rect
			(at 0 0.889 90)
			(size 0.508 0.508)
			(layers "B.Cu" "B.Mask" "B.Paste")
			(net "NIC_MDI_MNG_RX_DN")
		)
		(zone
			(layer "B.Cu")
			(hatch none 0.5)
			(connect_pads
				(clearance 0)
			)
			(min_thickness 0.25)
			(keepout
				(tracks not_allowed)
				(vias allowed)
				(pads allowed)
				(copperpour not_allowed)
				(footprints allowed)
			)
			(placement
				(enabled no)
				(sheetname "")
			)
			(fill
				(thermal_gap 0.5)
				(thermal_bridge_width 0.5)
				(island_removal_mode 0)
			)
			(polygon
				(pts
					(xy 476.999554 -2.259838) (xy 476.999554 -2.767838) (xy 477.380554 -2.767838) (xy 477.380554 -2.259838)
				)
			)
		)
		(zone
			(layer "B.Cu")
			(hatch none 0.5)
			(connect_pads
				(clearance 0)
			)
			(min_thickness 0.25)
			(keepout
				(tracks allowed)
				(vias not_allowed)
				(pads allowed)
				(copperpour not_allowed)
				(footprints allowed)
			)
			(placement
				(enabled no)
				(sheetname "")
			)
			(fill
				(thermal_gap 0.5)
				(thermal_bridge_width 0.5)
				(island_removal_mode 0)
			)
			(polygon
				(pts
					(xy 477.380554 -2.259838) (xy 477.380554 -2.767838) (xy 476.999554 -2.767838) (xy 476.999554 -2.259838)
				)
			)
		)
	)
	(footprint ""
		(layer "B.Cu")
		(at 318.9732 -34.2138 -90)
		(property "Reference" "R4T1"
			(at 0 0 90)
			(layer "B.SilkS")
			(hide yes)
			(effects
				(font
					(size 1.27 1.27)
				)
				(justify mirror)
			)
		)
		(property "Value" ""
			(at 0 0 90)
			(layer "B.Fab")
			(effects
				(font
					(size 1.27 1.27)
				)
				(justify mirror)
			)
		)
		(duplicate_pad_numbers_are_jumpers no)
		(fp_poly
			(pts
				(xy 0.2794 -0.1016) (xy -0.2794 -0.1016) (xy -0.2794 0.9906) (xy 0.2794 0.9906)
			)
			(stroke
				(width 0)
				(type default)
			)
			(fill no)
			(layer "B.CrtYd")
		)
		(fp_line
			(start -0.2794 0.9906)
			(end -0.2794 -0.1016)
			(stroke
				(width 0.1)
				(type default)
			)
			(layer "B.Fab")
		)
		(fp_line
			(start 0.2794 0.9906)
			(end -0.2794 0.9906)
			(stroke
				(width 0.1)
				(type default)
			)
			(layer "B.Fab")
		)
		(fp_line
			(start -0.2794 -0.1016)
			(end 0.2794 -0.1016)
			(stroke
				(width 0.1)
				(type default)
			)
			(layer "B.Fab")
		)
		(fp_line
			(start 0.2794 -0.1016)
			(end 0.2794 0.9906)
			(stroke
				(width 0.1)
				(type default)
			)
			(layer "B.Fab")
		)
		(pad "1" smd rect
			(at 0 0 90)
			(size 0.508 0.508)
			(layers "B.Cu" "B.Mask" "B.Paste")
			(net "FM_ADR_COMPLETE_DLY")
		)
		(pad "2" smd rect
			(at 0 0.889 90)
			(size 0.508 0.508)
			(layers "B.Cu" "B.Mask" "B.Paste")
			(net "FM_ADR_COMPLETE_R")
		)
		(zone
			(layer "B.Cu")
			(hatch none 0.5)
			(connect_pads
				(clearance 0)
			)
			(min_thickness 0.25)
			(keepout
				(tracks not_allowed)
				(vias allowed)
				(pads allowed)
				(copperpour not_allowed)
				(footprints allowed)
			)
			(placement
				(enabled no)
				(sheetname "")
			)
			(fill
				(thermal_gap 0.5)
				(thermal_bridge_width 0.5)
				(island_removal_mode 0)
			)
			(polygon
				(pts
					(xy 318.3382 -33.9598) (xy 318.3382 -34.4678) (xy 318.7192 -34.4678) (xy 318.7192 -33.9598)
				)
			)
		)
		(zone
			(layer "B.Cu")
			(hatch none 0.5)
			(connect_pads
				(clearance 0)
			)
			(min_thickness 0.25)
			(keepout
				(tracks allowed)
				(vias not_allowed)
				(pads allowed)
				(copperpour not_allowed)
				(footprints allowed)
			)
			(placement
				(enabled no)
				(sheetname "")
			)
			(fill
				(thermal_gap 0.5)
				(thermal_bridge_width 0.5)
				(island_removal_mode 0)
			)
			(polygon
				(pts
					(xy 318.7192 -33.9598) (xy 318.7192 -34.4678) (xy 318.3382 -34.4678) (xy 318.3382 -33.9598)
				)
			)
		)
	)
	(footprint ""
		(layer "B.Cu")
		(at 195.453 -8.122412 90)
		(property "Reference" "C6U9"
			(at 0 0 90)
			(layer "B.SilkS")
			(hide yes)
			(effects
				(font
					(size 1.27 1.27)
				)
				(justify mirror)
			)
		)
		(property "Value" ""
			(at 0 0 90)
			(layer "B.Fab")
			(effects
				(font
					(size 1.27 1.27)
				)
				(justify mirror)
			)
		)
		(duplicate_pad_numbers_are_jumpers no)
		(fp_poly
			(pts
				(xy -0.3048 -0.1016) (xy -0.3048 0.9906) (xy 0.3048 0.9906) (xy 0.3048 -0.1016)
			)
			(stroke
				(width 0)
				(type default)
			)
			(fill no)
			(layer "B.CrtYd")
		)
		(fp_line
			(start 0.3048 -0.1016)
			(end 0.3048 0.9906)
			(stroke
				(width 0.1)
				(type default)
			)
			(layer "B.Fab")
		)
		(fp_line
			(start -0.3048 -0.1016)
			(end 0.3048 -0.1016)
			(stroke
				(width 0.1)
				(type default)
			)
			(layer "B.Fab")
		)
		(fp_line
			(start 0.3048 0.9906)
			(end -0.3048 0.9906)
			(stroke
				(width 0.1)
				(type default)
			)
			(layer "B.Fab")
		)
		(fp_line
			(start -0.3048 0.9906)
			(end -0.3048 -0.1016)
			(stroke
				(width 0.1)
				(type default)
			)
			(layer "B.Fab")
		)
		(pad "1" smd rect
			(at 0 0 270)
			(size 0.508 0.508)
			(layers "B.Cu" "B.Mask" "B.Paste")
			(net "M_B_VREF")
		)
		(pad "2" smd rect
			(at 0 0.889 270)
			(size 0.508 0.508)
			(layers "B.Cu" "B.Mask" "B.Paste")
			(net "GND")
		)
		(zone
			(layer "B.Cu")
			(hatch none 0.5)
			(connect_pads
				(clearance 0)
			)
			(min_thickness 0.25)
			(keepout
				(tracks allowed)
				(vias not_allowed)
				(pads allowed)
				(copperpour not_allowed)
				(footprints allowed)
			)
			(placement
				(enabled no)
				(sheetname "")
			)
			(fill
				(thermal_gap 0.5)
				(thermal_bridge_width 0.5)
				(island_removal_mode 0)
			)
			(polygon
				(pts
					(xy 195.707 -8.376412) (xy 195.707 -7.868412) (xy 196.088 -7.868412) (xy 196.088 -8.376412)
				)
			)
		)
		(zone
			(layer "B.Cu")
			(hatch none 0.5)
			(connect_pads
				(clearance 0)
			)
			(min_thickness 0.25)
			(keepout
				(tracks not_allowed)
				(vias allowed)
				(pads allowed)
				(copperpour not_allowed)
				(footprints allowed)
			)
			(placement
				(enabled no)
				(sheetname "")
			)
			(fill
				(thermal_gap 0.5)
				(thermal_bridge_width 0.5)
				(island_removal_mode 0)
			)
			(polygon
				(pts
					(xy 196.088 -8.376412) (xy 196.088 -7.868412) (xy 195.707 -7.868412) (xy 195.707 -8.376412)
				)
			)
		)
	)
	(footprint ""
		(layer "B.Cu")
		(at 192.024 -134.874 180)
		(property "Reference" "C6M2"
			(at 0 0 0)
			(layer "B.SilkS")
			(hide yes)
			(effects
				(font
					(size 1.27 1.27)
				)
				(justify mirror)
			)
		)
		(property "Value" ""
			(at 0 0 0)
			(layer "B.Fab")
			(effects
				(font
					(size 1.27 1.27)
				)
				(justify mirror)
			)
		)
		(duplicate_pad_numbers_are_jumpers no)
		(fp_poly
			(pts
				(xy -0.3048 -0.1016) (xy -0.3048 0.9906) (xy 0.3048 0.9906) (xy 0.3048 -0.1016)
			)
			(stroke
				(width 0)
				(type default)
			)
			(fill no)
			(layer "B.CrtYd")
		)
		(fp_line
			(start 0.3048 0.9906)
			(end -0.3048 0.9906)
			(stroke
				(width 0.1)
				(type default)
			)
			(layer "B.Fab")
		)
		(fp_line
			(start 0.3048 -0.1016)
			(end 0.3048 0.9906)
			(stroke
				(width 0.1)
				(type default)
			)
			(layer "B.Fab")
		)
		(fp_line
			(start -0.3048 0.9906)
			(end -0.3048 -0.1016)
			(stroke
				(width 0.1)
				(type default)
			)
			(layer "B.Fab")
		)
		(fp_line
			(start -0.3048 -0.1016)
			(end 0.3048 -0.1016)
			(stroke
				(width 0.1)
				(type default)
			)
			(layer "B.Fab")
		)
		(pad "1" smd rect
			(at 0 0)
			(size 0.508 0.508)
			(layers "B.Cu" "B.Mask" "B.Paste")
			(net "M_D_CPU_VREF")
		)
		(pad "2" smd rect
			(at 0 0.889)
			(size 0.508 0.508)
			(layers "B.Cu" "B.Mask" "B.Paste")
			(net "GND")
		)
		(zone
			(layer "B.Cu")
			(hatch none 0.5)
			(connect_pads
				(clearance 0)
			)
			(min_thickness 0.25)
			(keepout
				(tracks not_allowed)
				(vias allowed)
				(pads allowed)
				(copperpour not_allowed)
				(footprints allowed)
			)
			(placement
				(enabled no)
				(sheetname "")
			)
			(fill
				(thermal_gap 0.5)
				(thermal_bridge_width 0.5)
				(island_removal_mode 0)
			)
			(polygon
				(pts
					(xy 191.77 -135.509) (xy 192.278 -135.509) (xy 192.278 -135.128) (xy 191.77 -135.128)
				)
			)
		)
		(zone
			(layer "B.Cu")
			(hatch none 0.5)
			(connect_pads
				(clearance 0)
			)
			(min_thickness 0.25)
			(keepout
				(tracks allowed)
				(vias not_allowed)
				(pads allowed)
				(copperpour not_allowed)
				(footprints allowed)
			)
			(placement
				(enabled no)
				(sheetname "")
			)
			(fill
				(thermal_gap 0.5)
				(thermal_bridge_width 0.5)
				(island_removal_mode 0)
			)
			(polygon
				(pts
					(xy 191.77 -135.128) (xy 192.278 -135.128) (xy 192.278 -135.509) (xy 191.77 -135.509)
				)
			)
		)
	)
)
